(kicad_pcb
	(version 20260206)
	(generator "pcbnew")
	(generator_version "10.0")
	(general
		(thickness 1.6)
		(legacy_teardrops no)
	)
	(paper "A4")
	(title_block
		(title "01162023_DA0F0TEBIF0_F0T_Expander_BD_F_brd_V02_OCP.brd")
		(comment 1 "Grand Teton / footprints 3744-3750 of 9728")
	)
	(layers
		(0 "F.Cu" signal "TOP")
		(4 "In1.Cu" signal "GND")
		(6 "In2.Cu" signal "VCC")
		(8 "In3.Cu" signal "VCC1")
		(10 "In4.Cu" signal "GND1")
		(12 "In5.Cu" signal "IN1")
		(14 "In6.Cu" signal "GND2")
		(16 "In7.Cu" signal "IN2")
		(18 "In8.Cu" signal "GND3")
		(20 "In9.Cu" signal "IN3")
		(22 "In10.Cu" signal "GND4")
		(24 "In11.Cu" signal "IN4")
		(26 "In12.Cu" signal "GND5")
		(28 "In13.Cu" signal "IN5")
		(30 "In14.Cu" signal "GND6")
		(32 "In15.Cu" signal "IN6")
		(34 "In16.Cu" signal "GND7")
		(2 "B.Cu" signal "BOTTOM")
		(9 "F.Adhes" user "F.Adhesive")
		(11 "B.Adhes" user "B.Adhesive")
		(13 "F.Paste" user "Package Geometry/Pastemask Top")
		(15 "B.Paste" user "Package Geometry/Pastemask Bottom")
		(5 "F.SilkS" user "Ref Des/Silkscreen Top")
		(7 "B.SilkS" user "Ref Des/Silkscreen Bottom")
		(1 "F.Mask" user "Board Geometry/Soldermask Top")
		(3 "B.Mask" user "Board Geometry/Soldermask Bottom")
		(17 "Dwgs.User" user "User.Drawings")
		(19 "Cmts.User" user "User.Comments")
		(21 "Eco1.User" user "User.Eco1")
		(23 "Eco2.User" user "User.Eco2")
		(25 "Edge.Cuts" user "Board Geometry/Outline")
		(27 "Margin" user)
		(31 "F.CrtYd" user "Package Geometry/Place Bound Top")
		(29 "B.CrtYd" user "Package Geometry/Place Bound Bottom")
		(35 "F.Fab" user "Ref Des/Assembly Top")
		(33 "B.Fab" user "Ref Des/Assembly Bottom")
	)
	(footprint ""
		(layer "F.Cu")
		(at 91.034108 -306.074572 90)
		(property "Reference" "R1239"
			(at 0 0 90)
			(layer "F.SilkS")
			(hide yes)
			(effects
				(font
					(size 1.27 1.27)
				)
			)
		)
		(property "Value" ""
			(at 0 0 90)
			(layer "F.Fab")
			(effects
				(font
					(size 1.27 1.27)
				)
			)
		)
		(duplicate_pad_numbers_are_jumpers no)
		(fp_line
			(start 0.7874 -0.4064)
			(end 0.7874 0.4064)
			(stroke
				(width 0.1524)
				(type default)
			)
			(layer "F.SilkS")
		)
		(fp_line
			(start -0.7874 -0.4064)
			(end 0.7874 -0.4064)
			(stroke
				(width 0.1524)
				(type default)
			)
			(layer "F.SilkS")
		)
		(fp_line
			(start 0.7874 0.4064)
			(end -0.7874 0.4064)
			(stroke
				(width 0.1524)
				(type default)
			)
			(layer "F.SilkS")
		)
		(fp_line
			(start -0.7874 0.4064)
			(end -0.7874 -0.4064)
			(stroke
				(width 0.1524)
				(type default)
			)
			(layer "F.SilkS")
		)
		(fp_line
			(start -0.12065 -0.305054)
			(end -0.12065 -0.2794)
			(stroke
				(width 0.1)
				(type default)
			)
			(layer "F.Fab")
		)
		(fp_line
			(start -0.67945 -0.305054)
			(end -0.12065 -0.305054)
			(stroke
				(width 0.1)
				(type default)
			)
			(layer "F.Fab")
		)
		(fp_line
			(start 0.67945 -0.3048)
			(end 0.67945 0.3048)
			(stroke
				(width 0.1)
				(type default)
			)
			(layer "F.Fab")
		)
		(fp_line
			(start 0.12065 -0.3048)
			(end 0.67945 -0.3048)
			(stroke
				(width 0.1)
				(type default)
			)
			(layer "F.Fab")
		)
		(fp_line
			(start 0.12065 -0.2794)
			(end 0.12065 -0.3048)
			(stroke
				(width 0.1)
				(type default)
			)
			(layer "F.Fab")
		)
		(fp_line
			(start -0.12065 -0.2794)
			(end 0.12065 -0.2794)
			(stroke
				(width 0.1)
				(type default)
			)
			(layer "F.Fab")
		)
		(fp_line
			(start 0.120396 0.2794)
			(end -0.12065 0.2794)
			(stroke
				(width 0.1)
				(type default)
			)
			(layer "F.Fab")
		)
		(fp_line
			(start -0.12065 0.2794)
			(end -0.12065 0.3048)
			(stroke
				(width 0.1)
				(type default)
			)
			(layer "F.Fab")
		)
		(fp_line
			(start 0.67945 0.3048)
			(end 0.120396 0.3048)
			(stroke
				(width 0.1)
				(type default)
			)
			(layer "F.Fab")
		)
		(fp_line
			(start 0.120396 0.3048)
			(end 0.120396 0.2794)
			(stroke
				(width 0.1)
				(type default)
			)
			(layer "F.Fab")
		)
		(fp_line
			(start -0.12065 0.3048)
			(end -0.67945 0.3048)
			(stroke
				(width 0.1)
				(type default)
			)
			(layer "F.Fab")
		)
		(fp_line
			(start -0.67945 0.3048)
			(end -0.67945 -0.305054)
			(stroke
				(width 0.1)
				(type default)
			)
			(layer "F.Fab")
		)
		(pad "1" smd circle
			(at -0.40005 0 90)
			(size 0 0)
			(layers "F.Cu" "F.Mask" "F.Paste")
			(net "PEX0_SPARE1")
		)
		(pad "2" smd circle
			(at 0.40005 0 90)
			(size 0 0)
			(layers "F.Cu" "F.Mask" "F.Paste")
			(net "P1V8_PEX")
		)
	)
	(footprint ""
		(layer "F.Cu")
		(at 418.092382 -32.739584 180)
		(property "Reference" "C716"
			(at 0 0 180)
			(layer "F.SilkS")
			(hide yes)
			(effects
				(font
					(size 1.27 1.27)
				)
			)
		)
		(property "Value" ""
			(at 0 0 180)
			(layer "F.Fab")
			(effects
				(font
					(size 1.27 1.27)
				)
			)
		)
		(duplicate_pad_numbers_are_jumpers no)
		(fp_line
			(start 0.299974 0.150114)
			(end -0.299974 0.150114)
			(stroke
				(width 0.1)
				(type default)
			)
			(layer "F.Fab")
		)
		(fp_line
			(start 0.299974 -0.150114)
			(end 0.299974 0.150114)
			(stroke
				(width 0.1)
				(type default)
			)
			(layer "F.Fab")
		)
		(fp_line
			(start -0.299974 0.150114)
			(end -0.299974 -0.150114)
			(stroke
				(width 0.1)
				(type default)
			)
			(layer "F.Fab")
		)
		(fp_line
			(start -0.299974 -0.150114)
			(end 0.299974 -0.150114)
			(stroke
				(width 0.1)
				(type default)
			)
			(layer "F.Fab")
		)
		(pad "1" smd rect
			(at -0.2667 0 180)
			(size 0.3048 0.381)
			(layers "F.Cu" "F.Mask" "F.Paste")
			(net "P5E_PEX3_STN2_TX_DP<38>")
		)
		(pad "2" smd rect
			(at 0.2667 0 180)
			(size 0.3048 0.381)
			(layers "F.Cu" "F.Mask" "F.Paste")
			(net "P5E_PEX3_STN2_TX_C_DP<38>")
		)
	)
	(footprint ""
		(layer "F.Cu")
		(at 36.2458 -261.663434)
		(property "Reference" "C3039"
			(at 0 0 0)
			(layer "F.SilkS")
			(hide yes)
			(effects
				(font
					(size 1.27 1.27)
				)
			)
		)
		(property "Value" ""
			(at 0 0 0)
			(layer "F.Fab")
			(effects
				(font
					(size 1.27 1.27)
				)
			)
		)
		(duplicate_pad_numbers_are_jumpers no)
		(fp_line
			(start -1.2954 -0.5842)
			(end 1.2954 -0.5842)
			(stroke
				(width 0.1524)
				(type default)
			)
			(layer "F.SilkS")
		)
		(fp_line
			(start -1.2954 0.5842)
			(end -1.2954 -0.5842)
			(stroke
				(width 0.1524)
				(type default)
			)
			(layer "F.SilkS")
		)
		(fp_line
			(start 1.2954 -0.5842)
			(end 1.2954 0.5842)
			(stroke
				(width 0.1524)
				(type default)
			)
			(layer "F.SilkS")
		)
		(fp_line
			(start 1.2954 0.5842)
			(end -1.2954 0.5842)
			(stroke
				(width 0.1524)
				(type default)
			)
			(layer "F.SilkS")
		)
		(fp_line
			(start -1.1938 -0.4064)
			(end -0.8636 -0.4064)
			(stroke
				(width 0.1)
				(type default)
			)
			(layer "F.Fab")
		)
		(fp_line
			(start -1.1938 0.4064)
			(end -1.1938 -0.4064)
			(stroke
				(width 0.1)
				(type default)
			)
			(layer "F.Fab")
		)
		(fp_line
			(start -0.8636 -0.4572)
			(end 0.8636 -0.4572)
			(stroke
				(width 0.1)
				(type default)
			)
			(layer "F.Fab")
		)
		(fp_line
			(start -0.8636 -0.4064)
			(end -0.8636 -0.4572)
			(stroke
				(width 0.1)
				(type default)
			)
			(layer "F.Fab")
		)
		(fp_line
			(start -0.8636 0.4064)
			(end -1.1938 0.4064)
			(stroke
				(width 0.1)
				(type default)
			)
			(layer "F.Fab")
		)
		(fp_line
			(start -0.8636 0.4572)
			(end -0.8636 0.4064)
			(stroke
				(width 0.1)
				(type default)
			)
			(layer "F.Fab")
		)
		(fp_line
			(start 0.8636 -0.4572)
			(end 0.8636 -0.4064)
			(stroke
				(width 0.1)
				(type default)
			)
			(layer "F.Fab")
		)
		(fp_line
			(start 0.8636 -0.4064)
			(end 1.1938 -0.4064)
			(stroke
				(width 0.1)
				(type default)
			)
			(layer "F.Fab")
		)
		(fp_line
			(start 0.8636 0.4064)
			(end 0.8636 0.4572)
			(stroke
				(width 0.1)
				(type default)
			)
			(layer "F.Fab")
		)
		(fp_line
			(start 0.8636 0.4572)
			(end -0.8636 0.4572)
			(stroke
				(width 0.1)
				(type default)
			)
			(layer "F.Fab")
		)
		(fp_line
			(start 1.1938 -0.4064)
			(end 1.1938 0.4064)
			(stroke
				(width 0.1)
				(type default)
			)
			(layer "F.Fab")
		)
		(fp_line
			(start 1.1938 0.4064)
			(end 0.8636 0.4064)
			(stroke
				(width 0.1)
				(type default)
			)
			(layer "F.Fab")
		)
		(pad "1" smd rect
			(at -0.7366 0 270)
			(size 0.7112 0.8128)
			(layers "F.Cu" "F.Mask" "F.Paste")
			(net "PCEPLL3_VDDA18_PEX0")
		)
		(pad "2" smd rect
			(at 0.7366 0 270)
			(size 0.7112 0.8128)
			(layers "F.Cu" "F.Mask" "F.Paste")
			(net "GND")
		)
	)
	(footprint ""
		(layer "F.Cu")
		(at 290.264342 -139.6238)
		(property "Reference" "R241"
			(at 0 0 0)
			(layer "F.SilkS")
			(hide yes)
			(effects
				(font
					(size 1.27 1.27)
				)
			)
		)
		(property "Value" ""
			(at 0 0 0)
			(layer "F.Fab")
			(effects
				(font
					(size 1.27 1.27)
				)
			)
		)
		(duplicate_pad_numbers_are_jumpers no)
		(fp_line
			(start -0.7874 -0.4064)
			(end 0.7874 -0.4064)
			(stroke
				(width 0.1524)
				(type default)
			)
			(layer "F.SilkS")
		)
		(fp_line
			(start -0.7874 0.4064)
			(end -0.7874 -0.4064)
			(stroke
				(width 0.1524)
				(type default)
			)
			(layer "F.SilkS")
		)
		(fp_line
			(start 0.7874 -0.4064)
			(end 0.7874 0.4064)
			(stroke
				(width 0.1524)
				(type default)
			)
			(layer "F.SilkS")
		)
		(fp_line
			(start 0.7874 0.4064)
			(end -0.7874 0.4064)
			(stroke
				(width 0.1524)
				(type default)
			)
			(layer "F.SilkS")
		)
		(fp_line
			(start -0.67945 -0.305054)
			(end -0.12065 -0.305054)
			(stroke
				(width 0.1)
				(type default)
			)
			(layer "F.Fab")
		)
		(fp_line
			(start -0.67945 0.3048)
			(end -0.67945 -0.305054)
			(stroke
				(width 0.1)
				(type default)
			)
			(layer "F.Fab")
		)
		(fp_line
			(start -0.12065 -0.305054)
			(end -0.12065 -0.2794)
			(stroke
				(width 0.1)
				(type default)
			)
			(layer "F.Fab")
		)
		(fp_line
			(start -0.12065 -0.2794)
			(end 0.12065 -0.2794)
			(stroke
				(width 0.1)
				(type default)
			)
			(layer "F.Fab")
		)
		(fp_line
			(start -0.12065 0.2794)
			(end -0.12065 0.3048)
			(stroke
				(width 0.1)
				(type default)
			)
			(layer "F.Fab")
		)
		(fp_line
			(start -0.12065 0.3048)
			(end -0.67945 0.3048)
			(stroke
				(width 0.1)
				(type default)
			)
			(layer "F.Fab")
		)
		(fp_line
			(start 0.120396 0.2794)
			(end -0.12065 0.2794)
			(stroke
				(width 0.1)
				(type default)
			)
			(layer "F.Fab")
		)
		(fp_line
			(start 0.120396 0.3048)
			(end 0.120396 0.2794)
			(stroke
				(width 0.1)
				(type default)
			)
			(layer "F.Fab")
		)
		(fp_line
			(start 0.12065 -0.3048)
			(end 0.67945 -0.3048)
			(stroke
				(width 0.1)
				(type default)
			)
			(layer "F.Fab")
		)
		(fp_line
			(start 0.12065 -0.2794)
			(end 0.12065 -0.3048)
			(stroke
				(width 0.1)
				(type default)
			)
			(layer "F.Fab")
		)
		(fp_line
			(start 0.67945 -0.3048)
			(end 0.67945 0.3048)
			(stroke
				(width 0.1)
				(type default)
			)
			(layer "F.Fab")
		)
		(fp_line
			(start 0.67945 0.3048)
			(end 0.120396 0.3048)
			(stroke
				(width 0.1)
				(type default)
			)
			(layer "F.Fab")
		)
		(pad "1" smd circle
			(at -0.40005 0)
			(size 0 0)
			(layers "F.Cu" "F.Mask" "F.Paste")
			(net "RST_SMB_NIC4_MUX_ISO_R_N")
		)
		(pad "2" smd circle
			(at 0.40005 0)
			(size 0 0)
			(layers "F.Cu" "F.Mask" "F.Paste")
			(net "RST_SMB_NIC4_MUX_ISO_N")
		)
	)
	(footprint ""
		(layer "F.Cu")
		(at 314.163456 -450.437758 -90)
		(property "Reference" "J51"
			(at -2.4257 -5.635752 90)
			(unlocked yes)
			(layer "F.SilkS")
			(effects
				(font
					(size 0.7874 0.5842)
					(thickness 0.1524)
				)
			)
		)
		(property "Value" ""
			(at 0 0 270)
			(layer "F.Fab")
			(effects
				(font
					(size 1.27 1.27)
				)
			)
		)
		(duplicate_pad_numbers_are_jumpers no)
		(fp_line
			(start 0 4.011168)
			(end -3.330702 -4.771136)
			(stroke
				(width 0.1524)
				(type default)
			)
			(layer "F.SilkS")
		)
		(fp_line
			(start -3.330702 -4.771136)
			(end 3.330702 -4.771136)
			(stroke
				(width 0.1524)
				(type default)
			)
			(layer "F.SilkS")
		)
		(fp_line
			(start 3.330702 -4.771136)
			(end 0 4.011168)
			(stroke
				(width 0.1524)
				(type default)
			)
			(layer "F.SilkS")
		)
		(fp_line
			(start 0 4.011168)
			(end -3.330702 -4.771136)
			(stroke
				(width 0.1)
				(type default)
			)
			(layer "F.Fab")
		)
		(fp_line
			(start -3.330702 -4.771136)
			(end 3.330702 -4.771136)
			(stroke
				(width 0.1)
				(type default)
			)
			(layer "F.Fab")
		)
		(fp_line
			(start 3.330702 -4.771136)
			(end 0 4.011168)
			(stroke
				(width 0.1)
				(type default)
			)
			(layer "F.Fab")
		)
		(pad "1" thru_hole circle
			(at 0 0 270)
			(size 2.159 2.159)
			(drill 1.7018)
			(layers "*.Cu" "*.Mask")
			(remove_unused_layers no)
			(net "COUPON_GND1")
			(clearance 0.0254)
			(thermal_gap 0.0254)
		)
		(pad "2" thru_hole circle
			(at -1.27 -3.348736 270)
			(size 2.159 2.159)
			(drill 1.7018)
			(layers "*.Cu" "*.Mask")
			(remove_unused_layers no)
			(net "TDR_SE_50_OHM_IN5")
			(clearance 0.0254)
			(thermal_gap 0.0254)
		)
		(pad "3" thru_hole circle
			(at 1.27 -3.348736 270)
			(size 2.159 2.159)
			(drill 1.7018)
			(layers "*.Cu" "*.Mask")
			(remove_unused_layers no)
			(net "TDR_SE_50_OHM_IN5")
			(clearance 0.0254)
			(thermal_gap 0.0254)
		)
	)
	(footprint ""
		(layer "F.Cu")
		(at 115.815872 -307.130958 -90)
		(property "Reference" "C4206"
			(at 0 0 270)
			(layer "F.SilkS")
			(hide yes)
			(effects
				(font
					(size 1.27 1.27)
				)
			)
		)
		(property "Value" ""
			(at 0 0 270)
			(layer "F.Fab")
			(effects
				(font
					(size 1.27 1.27)
				)
			)
		)
		(duplicate_pad_numbers_are_jumpers no)
		(fp_line
			(start -1.2954 0.5842)
			(end -1.2954 -0.5842)
			(stroke
				(width 0.1524)
				(type default)
			)
			(layer "F.SilkS")
		)
		(fp_line
			(start 1.2954 0.5842)
			(end -1.2954 0.5842)
			(stroke
				(width 0.1524)
				(type default)
			)
			(layer "F.SilkS")
		)
		(fp_line
			(start -1.2954 -0.5842)
			(end 1.2954 -0.5842)
			(stroke
				(width 0.1524)
				(type default)
			)
			(layer "F.SilkS")
		)
		(fp_line
			(start 1.2954 -0.5842)
			(end 1.2954 0.5842)
			(stroke
				(width 0.1524)
				(type default)
			)
			(layer "F.SilkS")
		)
		(fp_line
			(start -0.8636 0.4572)
			(end -0.8636 0.4064)
			(stroke
				(width 0.1)
				(type default)
			)
			(layer "F.Fab")
		)
		(fp_line
			(start 0.8636 0.4572)
			(end -0.8636 0.4572)
			(stroke
				(width 0.1)
				(type default)
			)
			(layer "F.Fab")
		)
		(fp_line
			(start -1.1938 0.4064)
			(end -1.1938 -0.4064)
			(stroke
				(width 0.1)
				(type default)
			)
			(layer "F.Fab")
		)
		(fp_line
			(start -0.8636 0.4064)
			(end -1.1938 0.4064)
			(stroke
				(width 0.1)
				(type default)
			)
			(layer "F.Fab")
		)
		(fp_line
			(start 0.8636 0.4064)
			(end 0.8636 0.4572)
			(stroke
				(width 0.1)
				(type default)
			)
			(layer "F.Fab")
		)
		(fp_line
			(start 1.1938 0.4064)
			(end 0.8636 0.4064)
			(stroke
				(width 0.1)
				(type default)
			)
			(layer "F.Fab")
		)
		(fp_line
			(start -1.1938 -0.4064)
			(end -0.8636 -0.4064)
			(stroke
				(width 0.1)
				(type default)
			)
			(layer "F.Fab")
		)
		(fp_line
			(start -0.8636 -0.4064)
			(end -0.8636 -0.4572)
			(stroke
				(width 0.1)
				(type default)
			)
			(layer "F.Fab")
		)
		(fp_line
			(start 0.8636 -0.4064)
			(end 1.1938 -0.4064)
			(stroke
				(width 0.1)
				(type default)
			)
			(layer "F.Fab")
		)
		(fp_line
			(start 1.1938 -0.4064)
			(end 1.1938 0.4064)
			(stroke
				(width 0.1)
				(type default)
			)
			(layer "F.Fab")
		)
		(fp_line
			(start -0.8636 -0.4572)
			(end 0.8636 -0.4572)
			(stroke
				(width 0.1)
				(type default)
			)
			(layer "F.Fab")
		)
		(fp_line
			(start 0.8636 -0.4572)
			(end 0.8636 -0.4064)
			(stroke
				(width 0.1)
				(type default)
			)
			(layer "F.Fab")
		)
		(pad "1" smd rect
			(at -0.7366 0 180)
			(size 0.7112 0.8128)
			(layers "F.Cu" "F.Mask" "F.Paste")
			(net "P0V8_SERDES_VDDA_PEX0_C4")
		)
		(pad "2" smd rect
			(at 0.7366 0 180)
			(size 0.7112 0.8128)
			(layers "F.Cu" "F.Mask" "F.Paste")
			(net "GND")
		)
	)
	(footprint ""
		(layer "F.Cu")
		(at 460.611982 -112.547654)
		(property "Reference" "PC837"
			(at 0 0 0)
			(layer "F.SilkS")
			(hide yes)
			(effects
				(font
					(size 1.27 1.27)
				)
			)
		)
		(property "Value" ""
			(at 0 0 0)
			(layer "F.Fab")
			(effects
				(font
					(size 1.27 1.27)
				)
			)
		)
		(duplicate_pad_numbers_are_jumpers no)
		(fp_line
			(start -0.7874 -0.4064)
			(end 0.7874 -0.4064)
			(stroke
				(width 0.1524)
				(type default)
			)
			(layer "F.SilkS")
		)
		(fp_line
			(start -0.7874 0.4064)
			(end -0.7874 -0.4064)
			(stroke
				(width 0.1524)
				(type default)
			)
			(layer "F.SilkS")
		)
		(fp_line
			(start 0.7874 -0.4064)
			(end 0.7874 0.4064)
			(stroke
				(width 0.1524)
				(type default)
			)
			(layer "F.SilkS")
		)
		(fp_line
			(start 0.7874 0.4064)
			(end -0.7874 0.4064)
			(stroke
				(width 0.1524)
				(type default)
			)
			(layer "F.SilkS")
		)
		(fp_line
			(start -0.67945 -0.305054)
			(end -0.12065 -0.305054)
			(stroke
				(width 0.1)
				(type default)
			)
			(layer "F.Fab")
		)
		(fp_line
			(start -0.67945 0.3048)
			(end -0.67945 -0.305054)
			(stroke
				(width 0.1)
				(type default)
			)
			(layer "F.Fab")
		)
		(fp_line
			(start -0.12065 -0.305054)
			(end -0.12065 -0.2794)
			(stroke
				(width 0.1)
				(type default)
			)
			(layer "F.Fab")
		)
		(fp_line
			(start -0.12065 -0.2794)
			(end 0.12065 -0.2794)
			(stroke
				(width 0.1)
				(type default)
			)
			(layer "F.Fab")
		)
		(fp_line
			(start -0.12065 0.2794)
			(end -0.12065 0.3048)
			(stroke
				(width 0.1)
				(type default)
			)
			(layer "F.Fab")
		)
		(fp_line
			(start -0.12065 0.3048)
			(end -0.67945 0.3048)
			(stroke
				(width 0.1)
				(type default)
			)
			(layer "F.Fab")
		)
		(fp_line
			(start 0.120396 0.2794)
			(end -0.12065 0.2794)
			(stroke
				(width 0.1)
				(type default)
			)
			(layer "F.Fab")
		)
		(fp_line
			(start 0.120396 0.3048)
			(end 0.120396 0.2794)
			(stroke
				(width 0.1)
				(type default)
			)
			(layer "F.Fab")
		)
		(fp_line
			(start 0.12065 -0.3048)
			(end 0.67945 -0.3048)
			(stroke
				(width 0.1)
				(type default)
			)
			(layer "F.Fab")
		)
		(fp_line
			(start 0.12065 -0.2794)
			(end 0.12065 -0.3048)
			(stroke
				(width 0.1)
				(type default)
			)
			(layer "F.Fab")
		)
		(fp_line
			(start 0.67945 -0.3048)
			(end 0.67945 0.3048)
			(stroke
				(width 0.1)
				(type default)
			)
			(layer "F.Fab")
		)
		(fp_line
			(start 0.67945 0.3048)
			(end 0.120396 0.3048)
			(stroke
				(width 0.1)
				(type default)
			)
			(layer "F.Fab")
		)
		(pad "1" smd circle
			(at -0.40005 0)
			(size 0 0)
			(layers "F.Cu" "F.Mask" "F.Paste")
			(net "P12V_NIC7_CO_ISET_R")
		)
		(pad "2" smd circle
			(at 0.40005 0)
			(size 0 0)
			(layers "F.Cu" "F.Mask" "F.Paste")
			(net "GND")
		)
	)
)
